# BASEBOARD_FAB2 (Tioga Pass) — schematic netlist excerpt (pin names and nets, part order shuffled) for the footprints in the layout excerpt that follows; sources: Cadence DE-HDL packaged netlist, KiCad conversion of Wiwynn_Tioga_Pass_MB.brd

FB7F1  FERRITE  22 1% FB  pkg SM  page 231 : A = P12V_STBY ; B = VR_FET_SW_P12V_STBY_PVPP_ABC
R7C16  RES  33.2 1% CHIP  pkg 0402  page 121 : A = SPI_PCH_CS0_R_N ; B = SPI_PCH_CS0_N
U25W9  TTL1G07_A  74LVC1G07 IC  pkg SOP  page 157 : A = PWRGD_DSW_PWROK ; Y = RST_BMC_SRST_N

(kicad_pcb
	(version 20260206)
	(generator "pcbnew")
	(generator_version "10.0")
	(general
		(thickness 1.6)
		(legacy_teardrops no)
	)
	(paper "A4")
	(title_block
		(title "Wiwynn_Tioga_Pass_MB.brd")
		(comment 1 "Tioga Pass / footprints 234-236 of 4770")
	)
	(layers
		(0 "F.Cu" signal "TOP")
		(4 "In1.Cu" signal "L2GND")
		(6 "In2.Cu" signal "L3")
		(8 "In3.Cu" signal "L4GND")
		(10 "In4.Cu" signal "L5")
		(12 "In5.Cu" signal "L6GND")
		(14 "In6.Cu" signal "L7VCC")
		(16 "In7.Cu" signal "L8VCC")
		(18 "In8.Cu" signal "L9GND")
		(20 "In9.Cu" signal "L10")
		(22 "In10.Cu" signal "L11GND")
		(24 "In11.Cu" signal "L12")
		(26 "In12.Cu" signal "L13GND")
		(2 "B.Cu" signal "BOTTOM")
		(9 "F.Adhes" user "F.Adhesive")
		(11 "B.Adhes" user "B.Adhesive")
		(13 "F.Paste" user "Package Geometry/Pastemask Top")
		(15 "B.Paste" user "Package Geometry/Pastemask Bottom")
		(5 "F.SilkS" user "Ref Des/Silkscreen Top")
		(7 "B.SilkS" user "Ref Des/Silkscreen Bottom")
		(1 "F.Mask" user "Board Geometry/Soldermask Top")
		(3 "B.Mask" user "Board Geometry/Soldermask Bottom")
		(17 "Dwgs.User" user "User.Drawings")
		(19 "Cmts.User" user "User.Comments")
		(21 "Eco1.User" user "User.Eco1")
		(23 "Eco2.User" user "User.Eco2")
		(25 "Edge.Cuts" user "Board Geometry/Outline")
		(27 "Margin" user)
		(31 "F.CrtYd" user "Package Geometry/Place Bound Top")
		(29 "B.CrtYd" user "Package Geometry/Place Bound Bottom")
		(35 "F.Fab" user "Ref Des/Assembly Top")
		(33 "B.Fab" user "Ref Des/Assembly Bottom")
	)
	(footprint ""
		(layer "F.Cu")
		(at 352.9838 -30.353)
		(property "Reference" "FB7F1"
			(at 0 0 0)
			(layer "F.SilkS")
			(hide yes)
			(effects
				(font
					(size 1.27 1.27)
				)
			)
		)
		(property "Value" ""
			(at 0 0 0)
			(layer "F.Fab")
			(effects
				(font
					(size 1.27 1.27)
				)
			)
		)
		(duplicate_pad_numbers_are_jumpers no)
		(fp_rect
			(start -0.7239 2.03835)
			(end 0.7239 -0.26035)
			(stroke
				(width 0)
				(type default)
			)
			(fill no)
			(layer "F.CrtYd")
		)
		(fp_line
			(start -0.7239 -0.26035)
			(end 0.7239 -0.26035)
			(stroke
				(width 0.1)
				(type default)
			)
			(layer "F.Fab")
		)
		(fp_line
			(start -0.7239 2.03835)
			(end -0.7239 -0.26035)
			(stroke
				(width 0.1)
				(type default)
			)
			(layer "F.Fab")
		)
		(fp_line
			(start 0.7239 -0.26035)
			(end 0.7239 2.03835)
			(stroke
				(width 0.1)
				(type default)
			)
			(layer "F.Fab")
		)
		(fp_line
			(start 0.7239 2.03835)
			(end -0.7239 2.03835)
			(stroke
				(width 0.1)
				(type default)
			)
			(layer "F.Fab")
		)
		(pad "1" smd rect
			(at 0 0)
			(size 1.27 1.016)
			(layers "F.Cu" "F.Mask" "F.Paste")
			(net "P12V_STBY")
		)
		(pad "2" smd rect
			(at 0 1.778)
			(size 1.27 1.016)
			(layers "F.Cu" "F.Mask" "F.Paste")
			(net "VR_FET_SW_P12V_STBY_PVPP_ABC")
		)
		(zone
			(layer "F.Cu")
			(hatch none 0.5)
			(connect_pads
				(clearance 0)
			)
			(min_thickness 0.25)
			(keepout
				(tracks not_allowed)
				(vias allowed)
				(pads allowed)
				(copperpour not_allowed)
				(footprints allowed)
			)
			(placement
				(enabled no)
				(sheetname "")
			)
			(fill
				(thermal_gap 0.5)
				(thermal_bridge_width 0.5)
				(island_removal_mode 0)
			)
			(polygon
				(pts
					(xy 353.6188 -29.845) (xy 353.6188 -29.083) (xy 353.5299 -29.083) (xy 352.3488 -29.083) (xy 352.3488 -29.845)
				)
			)
		)
	)
	(footprint ""
		(layer "F.Cu")
		(at 375.92 -88.2015)
		(property "Reference" "R7C16"
			(at 0 0 0)
			(layer "F.SilkS")
			(hide yes)
			(effects
				(font
					(size 1.27 1.27)
				)
			)
		)
		(property "Value" ""
			(at 0 0 0)
			(layer "F.Fab")
			(effects
				(font
					(size 1.27 1.27)
				)
			)
		)
		(duplicate_pad_numbers_are_jumpers no)
		(fp_poly
			(pts
				(xy -0.2794 -0.1016) (xy 0.2794 -0.1016) (xy 0.2794 0.9906) (xy -0.2794 0.9906)
			)
			(stroke
				(width 0)
				(type default)
			)
			(fill no)
			(layer "F.CrtYd")
		)
		(fp_line
			(start -0.2794 -0.1016)
			(end -0.2794 0.9906)
			(stroke
				(width 0.1)
				(type default)
			)
			(layer "F.Fab")
		)
		(fp_line
			(start -0.2794 0.9906)
			(end 0.2794 0.9906)
			(stroke
				(width 0.1)
				(type default)
			)
			(layer "F.Fab")
		)
		(fp_line
			(start 0.2794 -0.1016)
			(end -0.2794 -0.1016)
			(stroke
				(width 0.1)
				(type default)
			)
			(layer "F.Fab")
		)
		(fp_line
			(start 0.2794 0.9906)
			(end 0.2794 -0.1016)
			(stroke
				(width 0.1)
				(type default)
			)
			(layer "F.Fab")
		)
		(pad "1" smd rect
			(at 0 0)
			(size 0.508 0.508)
			(layers "F.Cu" "F.Mask" "F.Paste")
			(net "SPI_PCH_CS0_R_N")
		)
		(pad "2" smd rect
			(at 0 0.889)
			(size 0.508 0.508)
			(layers "F.Cu" "F.Mask" "F.Paste")
			(net "SPI_PCH_CS0_N")
		)
		(zone
			(layer "F.Cu")
			(hatch none 0.5)
			(connect_pads
				(clearance 0)
			)
			(min_thickness 0.25)
			(keepout
				(tracks allowed)
				(vias not_allowed)
				(pads allowed)
				(copperpour not_allowed)
				(footprints allowed)
			)
			(placement
				(enabled no)
				(sheetname "")
			)
			(fill
				(thermal_gap 0.5)
				(thermal_bridge_width 0.5)
				(island_removal_mode 0)
			)
			(polygon
				(pts
					(xy 375.666 -87.9475) (xy 376.174 -87.9475) (xy 376.174 -87.5665) (xy 375.666 -87.5665)
				)
			)
		)
		(zone
			(layer "F.Cu")
			(hatch none 0.5)
			(connect_pads
				(clearance 0)
			)
			(min_thickness 0.25)
			(keepout
				(tracks not_allowed)
				(vias allowed)
				(pads allowed)
				(copperpour not_allowed)
				(footprints allowed)
			)
			(placement
				(enabled no)
				(sheetname "")
			)
			(fill
				(thermal_gap 0.5)
				(thermal_bridge_width 0.5)
				(island_removal_mode 0)
			)
			(polygon
				(pts
					(xy 375.666 -87.5665) (xy 376.174 -87.5665) (xy 376.174 -87.9475) (xy 375.666 -87.9475)
				)
			)
		)
	)
	(footprint ""
		(layer "F.Cu")
		(at 446.532 -12.954 90)
		(property "Reference" "U25W9"
			(at -0.14986 2.621788 90)
			(unlocked yes)
			(layer "F.SilkS")
			(effects
				(font
					(size 1.27 0.964946)
					(thickness 0.000001)
				)
				(justify left)
			)
		)
		(property "Value" ""
			(at 0 0 90)
			(layer "F.Fab")
			(effects
				(font
					(size 1.27 1.27)
				)
			)
		)
		(duplicate_pad_numbers_are_jumpers no)
		(fp_circle
			(center -0.4699 -0.8382)
			(end -0.4699 -0.7112)
			(stroke
				(width 0.254)
				(type default)
			)
			(fill no)
			(layer "F.SilkS")
		)
		(fp_poly
			(pts
				(xy 0.21463 -0.450088) (xy 1.56337 -0.450088) (xy 1.56337 1.75006) (xy 0.21463 1.75006)
			)
			(stroke
				(width 0)
				(type default)
			)
			(fill no)
			(layer "F.CrtYd")
		)
		(fp_line
			(start 1.56337 -0.450088)
			(end 1.56337 1.75006)
			(stroke
				(width 0.1)
				(type default)
			)
			(layer "F.Fab")
		)
		(fp_line
			(start 0.21463 -0.450088)
			(end 1.56337 -0.450088)
			(stroke
				(width 0.1)
				(type default)
			)
			(layer "F.Fab")
		)
		(fp_line
			(start 1.56337 1.75006)
			(end 0.21463 1.75006)
			(stroke
				(width 0.1)
				(type default)
			)
			(layer "F.Fab")
		)
		(fp_line
			(start 0.21463 1.75006)
			(end 0.21463 -0.450088)
			(stroke
				(width 0.1)
				(type default)
			)
			(layer "F.Fab")
		)
		(fp_circle
			(center -0.4699 -0.8382)
			(end -0.4699 -0.7112)
			(stroke
				(width 0.254)
				(type default)
			)
			(fill no)
			(layer "F.Fab")
		)
		(pad "1" smd rect
			(at 0 0 90)
			(size 1.016 0.381)
			(layers "F.Cu" "F.Mask" "F.Paste")
			(net "Net_6489")
		)
		(pad "2" smd rect
			(at 0 0.649986 90)
			(size 1.016 0.381)
			(layers "F.Cu" "F.Mask" "F.Paste")
			(net "PWRGD_DSW_PWROK")
		)
		(pad "3" smd rect
			(at 0 1.299972 90)
			(size 1.016 0.381)
			(layers "F.Cu" "F.Mask" "F.Paste")
			(net "GND")
		)
		(pad "4" smd rect
			(at 1.778 1.299972 90)
			(size 1.016 0.381)
			(layers "F.Cu" "F.Mask" "F.Paste")
			(net "RST_BMC_SRST_N")
		)
		(pad "5" smd rect
			(at 1.778 0 90)
			(size 1.016 0.381)
			(layers "F.Cu" "F.Mask" "F.Paste")
			(net "P3V3_STBY")
		)
	)
)
